(kicad_pcb
	(version 20260206)
	(generator "pcbnew")
	(generator_version "10.0")
	(general
		(thickness 1.6)
		(legacy_teardrops no)
	)
	(paper "A4")
	(title_block
		(title "03242023_DA0F0TMBIJ0_F0T_Motherboard_J_brd_V01_OCP.brd")
		(comment 1 "Grand Teton / footprints 3034-3034 of 6105")
	)
	(layers
		(0 "F.Cu" signal "TOP")
		(4 "In1.Cu" signal "GND")
		(6 "In2.Cu" signal "IN1")
		(8 "In3.Cu" signal "GND1")
		(10 "In4.Cu" signal "IN2")
		(12 "In5.Cu" signal "GND2")
		(14 "In6.Cu" signal "IN3")
		(16 "In7.Cu" signal "GND3")
		(18 "In8.Cu" signal "VCC")
		(20 "In9.Cu" signal "VCC1")
		(22 "In10.Cu" signal "GND4")
		(24 "In11.Cu" signal "IN4")
		(26 "In12.Cu" signal "GND5")
		(28 "In13.Cu" signal "IN5")
		(30 "In14.Cu" signal "GND6")
		(32 "In15.Cu" signal "IN6")
		(34 "In16.Cu" signal "GND7")
		(2 "B.Cu" signal "BOTTOM")
		(9 "F.Adhes" user "F.Adhesive")
		(11 "B.Adhes" user "B.Adhesive")
		(13 "F.Paste" user "Package Geometry/Pastemask Top")
		(15 "B.Paste" user "Package Geometry/Pastemask Bottom")
		(5 "F.SilkS" user "Ref Des/Silkscreen Top")
		(7 "B.SilkS" user "Ref Des/Silkscreen Bottom")
		(1 "F.Mask" user "Board Geometry/Soldermask Top")
		(3 "B.Mask" user "Board Geometry/Soldermask Bottom")
		(17 "Dwgs.User" user "User.Drawings")
		(19 "Cmts.User" user "User.Comments")
		(21 "Eco1.User" user "User.Eco1")
		(23 "Eco2.User" user "User.Eco2")
		(25 "Edge.Cuts" user "Board Geometry/Outline")
		(27 "Margin" user)
		(31 "F.CrtYd" user "Package Geometry/Place Bound Top")
		(29 "B.CrtYd" user "Package Geometry/Place Bound Bottom")
		(35 "F.Fab" user "Ref Des/Assembly Top")
		(33 "B.Fab" user "Ref Des/Assembly Bottom")
	)
	(footprint ""
		(layer "F.Cu")
		(at 68.081144 -106.319066)
		(property "Reference" "R3732"
			(at 0 0 0)
			(layer "F.SilkS")
			(hide yes)
			(effects
				(font
					(size 1.27 1.27)
				)
			)
		)
		(property "Value" ""
			(at 0 0 0)
			(layer "F.Fab")
			(effects
				(font
					(size 1.27 1.27)
				)
			)
		)
		(duplicate_pad_numbers_are_jumpers no)
		(fp_line
			(start -0.7874 -0.4064)
			(end 0.7874 -0.4064)
			(stroke
				(width 0.1524)
				(type default)
			)
			(layer "F.SilkS")
		)
		(fp_line
			(start -0.7874 0.4064)
			(end -0.7874 -0.4064)
			(stroke
				(width 0.1524)
				(type default)
			)
			(layer "F.SilkS")
		)
		(fp_line
			(start 0.7874 -0.4064)
			(end 0.7874 0.4064)
			(stroke
				(width 0.1524)
				(type default)
			)
			(layer "F.SilkS")
		)
		(fp_line
			(start 0.7874 0.4064)
			(end -0.7874 0.4064)
			(stroke
				(width 0.1524)
				(type default)
			)
			(layer "F.SilkS")
		)
		(fp_line
			(start -0.67945 -0.305054)
			(end -0.12065 -0.305054)
			(stroke
				(width 0.1)
				(type default)
			)
			(layer "F.Fab")
		)
		(fp_line
			(start -0.67945 0.3048)
			(end -0.67945 -0.305054)
			(stroke
				(width 0.1)
				(type default)
			)
			(layer "F.Fab")
		)
		(fp_line
			(start -0.12065 -0.305054)
			(end -0.12065 -0.2794)
			(stroke
				(width 0.1)
				(type default)
			)
			(layer "F.Fab")
		)
		(fp_line
			(start -0.12065 -0.2794)
			(end 0.12065 -0.2794)
			(stroke
				(width 0.1)
				(type default)
			)
			(layer "F.Fab")
		)
		(fp_line
			(start -0.12065 0.2794)
			(end -0.12065 0.3048)
			(stroke
				(width 0.1)
				(type default)
			)
			(layer "F.Fab")
		)
		(fp_line
			(start -0.12065 0.3048)
			(end -0.67945 0.3048)
			(stroke
				(width 0.1)
				(type default)
			)
			(layer "F.Fab")
		)
		(fp_line
			(start 0.120396 0.2794)
			(end -0.12065 0.2794)
			(stroke
				(width 0.1)
				(type default)
			)
			(layer "F.Fab")
		)
		(fp_line
			(start 0.120396 0.3048)
			(end 0.120396 0.2794)
			(stroke
				(width 0.1)
				(type default)
			)
			(layer "F.Fab")
		)
		(fp_line
			(start 0.12065 -0.3048)
			(end 0.67945 -0.3048)
			(stroke
				(width 0.1)
				(type default)
			)
			(layer "F.Fab")
		)
		(fp_line
			(start 0.12065 -0.2794)
			(end 0.12065 -0.3048)
			(stroke
				(width 0.1)
				(type default)
			)
			(layer "F.Fab")
		)
		(fp_line
			(start 0.67945 -0.3048)
			(end 0.67945 0.3048)
			(stroke
				(width 0.1)
				(type default)
			)
			(layer "F.Fab")
		)
		(fp_line
			(start 0.67945 0.3048)
			(end 0.120396 0.3048)
			(stroke
				(width 0.1)
				(type default)
			)
			(layer "F.Fab")
		)
		(pad "1" smd circle
			(at -0.40005 0)
			(size 0 0)
			(layers "F.Cu" "F.Mask" "F.Paste")
			(net "P3V3_AUX")
		)
		(pad "2" smd circle
			(at 0.40005 0)
			(size 0 0)
			(layers "F.Cu" "F.Mask" "F.Paste")
			(net "SMB_LM75_3_3V3AUX_SDA")
		)
	)
)
